# S9S_MB_2U (Grand Teton) — schematic netlist excerpt (pin names and nets, part order shuffled) for the footprints in the layout excerpt that follows; sources: Cadence DE-HDL packaged netlist, KiCad conversion of 03242023_DA0F0TMBIJ0_F0T_Motherboard_J_brd_V01_OCP.brd

J5  SCONN288_ADR50017P130CC  SCONN288_ADR50017-P130CC IO  pkg DDR288S_1-1VXB  page 86
  VIN_BULK0  = P12V_S3_AUX_CPU0_NVDIMM
  RFU0  = TP_CHC_CPU0_DIMM1_FRU_0
  VIN_MGMT  = P3V3_AUX
  HSCL  = I3C_SPD_DDRABCD_CPU0_LVC1_SCL_4
  HSDA  = I3C_SPD_DDRABCD_CPU0_LVC1_SDA
  VSS0  = GND
  DQ0_A  = M_C_CPU0_SA_DQ<0>
  VSS1  = GND
  DQ1_A  = M_C_CPU0_SA_DQ<1>
  VSS2  = GND
  DQS0_A_T  = M_C_CPU0_SA_DQS_DP<0>
  DQS0_A_C  = M_C_CPU0_SA_DQS_DN<0>
  VSS3  = GND
  DQ4_A  = M_C_CPU0_SA_DQ<4>
  VSS4  = GND
  DQ5_A  = M_C_CPU0_SA_DQ<5>
  VSS5  = GND
  DQ8_A  = M_C_CPU0_SA_DQ<8>
  VSS6  = GND
  DQ9_A  = M_C_CPU0_SA_DQ<9>
  VSS7  = GND
  DQS1_A_T  = M_C_CPU0_SA_DQS_DP<1>
  DQS1_A_C  = M_C_CPU0_SA_DQS_DN<1>
  VSS8  = GND
  DQ12_A  = M_C_CPU0_SA_DQ<12>
  VSS9  = GND
  DQ13_A  = M_C_CPU0_SA_DQ<13>
  VSS10  = GND
  DQ16_A  = M_C_CPU0_SA_DQ<16>
  VSS11  = GND
  DQ17_A  = M_C_CPU0_SA_DQ<17>
  VSS12  = GND
  DQS2_A_T  = M_C_CPU0_SA_DQS_DP<2>
  DQS2_A_C  = M_C_CPU0_SA_DQS_DN<2>
  VSS13  = GND
  DQ20_A  = M_C_CPU0_SA_DQ<20>
  VSS14  = GND
  DQ21_A  = M_C_CPU0_SA_DQ<21>
  VSS15  = GND
  DQ24_A  = M_C_CPU0_SA_DQ<24>
  VSS16  = GND
  DQ25_A  = M_C_CPU0_SA_DQ<25>
  VSS17  = GND
  DQS3_A_T  = M_C_CPU0_SA_DQS_DP<3>
  DQS3_A_C  = M_C_CPU0_SA_DQS_DN<3>
  VSS18  = GND
  DQ28_A  = M_C_CPU0_SA_DQ<28>
  VSS19  = GND
  DQ29_A  = M_C_CPU0_SA_DQ<29>
  VSS20  = GND
  CB0_A  = M_C_CPU0_SA_CB<0>
  VSS21  = GND
  CB1_A  = M_C_CPU0_SA_CB<1>
  VSS22  = GND
  DQS4_A_T  = M_C_CPU0_SA_DQS_DP<4>
  DQS4_A_C  = M_C_CPU0_SA_DQS_DN<4>
  VSS23  = GND
  CB4_A  = M_C_CPU0_SA_CB<4>
  VSS24  = GND
  CB5_A  = M_C_CPU0_SA_CB<5>
  VSS25  = GND
  ALERT_N  = M_C_CPU0_ALERT_N
  VSS26  = GND
  CS0_A_N  = M_C_CPU0_SA_CS_N<0>
  VSS27  = GND
  CA0_A  = M_C_CPU0_SA_CA<0>
  VSS28  = GND
  CA2_A  = M_C_CPU0_SA_CA<2>
  VSS29  = GND
  CA4_A  = M_C_CPU0_SA_CA<4>
  VSS30  = GND
  CA6_A  = M_C_CPU0_SA_CA<6>
  VSS31  = GND
  PAR_A  = M_C_CPU0_SA_PAR
  VSS32  = GND
  CA0_B  = M_C_CPU0_SB_CA<0>
  VSS33  = GND
  CA2_B  = M_C_CPU0_SB_CA<2>
  VSS34  = GND
  CA4_B  = M_C_CPU0_SB_CA<4>
  VSS35  = GND
  CA6_B  = M_C_CPU0_SB_CA<6>
  VSS36  = GND
  CS0_B_N  = M_C_CPU0_SB_CS_N<0>
  VSS37  = GND
  \lbd||rsp_a_n\  = M_C_CPU0_SA_RSP<0>
  \lbs||rsp_b_n\  = M_C_CPU0_SB_RSP<0>
  VSS38  = GND
  CB4_B  = M_C_CPU0_SB_CB<4>
  VSS39  = GND
  CB5_B  = M_C_CPU0_SB_CB<5>
  VSS40  = GND
  \dqs9_b_t||tdqs9_b_t||dbi4_b_n\  = M_C_CPU0_SB_DQS_DP<9>
  \dqs9_b_c||tdqs9_b_c\  = M_C_CPU0_SB_DQS_DN<9>
  VSS41  = GND
  CB0_B  = M_C_CPU0_SB_CB<0>
  VSS42  = GND
  CB1_B  = M_C_CPU0_SB_CB<1>
  VSS43  = GND
  DQ0_B  = M_C_CPU0_SB_DQ<0>
  VSS44  = GND
  DQ1_B  = M_C_CPU0_SB_DQ<1>
  VSS45  = GND
  DQS0_B_T  = M_C_CPU0_SB_DQS_DP<0>
  DQS0_B_C  = M_C_CPU0_SB_DQS_DN<0>
  VSS46  = GND
  DQ4_B  = M_C_CPU0_SB_DQ<4>
  VSS47  = GND
  DQ5_B  = M_C_CPU0_SB_DQ<5>
  VSS48  = GND
  DQ8_B  = M_C_CPU0_SB_DQ<8>
  VSS49  = GND
  DQ9_B  = M_C_CPU0_SB_DQ<9>
  VSS50  = GND
  DQS1_B_T  = M_C_CPU0_SB_DQS_DP<1>
  DQS1_B_C  = M_C_CPU0_SB_DQS_DN<1>
  VSS51  = GND
  DQ12_B  = M_C_CPU0_SB_DQ<12>
  VSS52  = GND
  DQ13_B  = M_C_CPU0_SB_DQ<13>
  VSS53  = GND
  DQ16_B  = M_C_CPU0_SB_DQ<16>
  VSS54  = GND
  DQ17_B  = M_C_CPU0_SB_DQ<17>
  VSS55  = GND
  DQS2_B_T  = M_C_CPU0_SB_DQS_DP<2>
  DQS2_B_C  = M_C_CPU0_SB_DQS_DN<2>
  VSS56  = GND
  DQ20_B  = M_C_CPU0_SB_DQ<20>
  VSS57  = GND
  DQ21_B  = M_C_CPU0_SB_DQ<21>
  VSS58  = GND
  DQ24_B  = M_C_CPU0_SB_DQ<24>
  VSS59  = GND
  DQ25_B  = M_C_CPU0_SB_DQ<25>
  VSS60  = GND
  DQS3_B_T  = M_C_CPU0_SB_DQS_DP<3>
  DQS3_B_C  = M_C_CPU0_SB_DQS_DN<3>
  VSS61  = GND
  DQ28_B  = M_C_CPU0_SB_DQ<28>
  VSS62  = GND
  DQ29_B  = M_C_CPU0_SB_DQ<29>
  VSS63  = GND
  RFU1  = TP_CHC_CPU0_DIMM1_FRU_1
  VIN_BULK1  = P12V_S3_AUX_CPU0_NVDIMM
  VIN_BULK2  = P12V_S3_AUX_CPU0_NVDIMM
  \pwr_good||fail_n\  = PWRGD_CHC_CPU0_DIMM1
  HSA  = PD_CHC_CPU0_DIMM1_SAA
  RFU2  = TP_CHC_CPU0_DIMM1_FRU_2
  RFU3  = TP_CHC_CPU0_DIMM1_FRU_3
  VSS64  = GND
  DQ2_A  = M_C_CPU0_SA_DQ<2>
  VSS65  = GND
  DQ3_A  = M_C_CPU0_SA_DQ<3>
  VSS66  = GND
  \dqs5_a_c||tdqs5_a_c||dqs5_a_t||tdqs5_a_t\  = M_C_CPU0_SA_DQS_DN<5>
  \dqs5_a_t||tdqs5_a_t\  = M_C_CPU0_SA_DQS_DP<5>
  VSS67  = GND
  DQ6_A  = M_C_CPU0_SA_DQ<6>
  VSS68  = GND
  DQ7_A  = M_C_CPU0_SA_DQ<7>
  VSS69  = GND
  DQ10_A  = M_C_CPU0_SA_DQ<10>
  VSS70  = GND
  DQ11_A  = M_C_CPU0_SA_DQ<11>
  VSS71  = GND
  \dqs6_a_c||tdqs6_a_c||dqs6_a_t||tdqs6_a_t\  = M_C_CPU0_SA_DQS_DN<6>
  \dqs6_a_t||tdqs6_a_t\  = M_C_CPU0_SA_DQS_DP<6>
  VSS72  = GND
  DQ14_A  = M_C_CPU0_SA_DQ<14>
  VSS73  = GND
  DQ15_A  = M_C_CPU0_SA_DQ<15>
  VSS74  = GND
  DQ18_A  = M_C_CPU0_SA_DQ<18>
  VSS75  = GND
  DQ19_A  = M_C_CPU0_SA_DQ<19>
  VSS76  = GND
  \dqs7_a_c||tdqs7_a_c\  = M_C_CPU0_SA_DQS_DN<7>
  \dqs7_a_t||tdqs7_a_t\  = M_C_CPU0_SA_DQS_DP<7>
  VSS77  = GND
  DQ22_A  = M_C_CPU0_SA_DQ<22>
  VSS78  = GND
  DQ23_A  = M_C_CPU0_SA_DQ<23>
  VSS79  = GND
  DQ26_A  = M_C_CPU0_SA_DQ<26>
  VSS80  = GND
  DQ27_A  = M_C_CPU0_SA_DQ<27>
  VSS81  = GND
  \dqs8_a_c||tdqs8_a_c\  = M_C_CPU0_SA_DQS_DN<8>
  \dqs8_a_t||tdqs8_a_t\  = M_C_CPU0_SA_DQS_DP<8>
  VSS82  = GND
  DQ30_A  = M_C_CPU0_SA_DQ<30>
  VSS83  = GND
  DQ31_A  = M_C_CPU0_SA_DQ<31>
  VSS84  = GND
  CB2_A  = M_C_CPU0_SA_CB<2>
  VSS85  = GND
  CB3_A  = M_C_CPU0_SA_CB<3>
  VSS86  = GND
  \dqs9_a_c||tdqs9_a_c\  = M_C_CPU0_SA_DQS_DN<9>
  \dqs9_a_t||tdqs9_a_t\  = M_C_CPU0_SA_DQS_DP<9>
  VSS87  = GND
  CB6_A  = M_C_CPU0_SA_CB<6>
  VSS88  = GND
  CB7_A  = M_C_CPU0_SA_CB<7>
  VSS89  = GND
  RESET_N  = RST_M_CD_CPU0_FPGA_N
  VSS90  = GND
  CS1_A_N  = M_C_CPU0_SA_CS_N<1>
  VSS91  = GND
  CA1_A  = M_C_CPU0_SA_CA<1>
  VSS92  = GND
  CA3_A  = M_C_CPU0_SA_CA<3>
  VSS93  = GND
  CA5_A  = M_C_CPU0_SA_CA<5>
  VSS94  = GND
  CK_T  = M_C_CPU0_CLK_DP<0>
  CK_C  = M_C_CPU0_CLK_DN<0>
  VSS95  = GND
  RFU4  = TP_CHC_CPU0_DIMM1_FRU_4
  CA1_B  = M_C_CPU0_SB_CA<1>
  VSS96  = GND
  CA3_B  = M_C_CPU0_SB_CA<3>
  VSS97  = GND
  CA5_B  = M_C_CPU0_SB_CA<5>
  VSS98  = GND
  PAR_B  = M_C_CPU0_SB_PAR
  VSS99  = GND
  CS1_B_N  = M_C_CPU0_SB_CS_N<1>
  VSS100  = GND
  RFU5  = TP_CHC_CPU0_DIMM1_FRU_5
  RFU6  = TP_CHC_CPU0_DIMM1_FRU_6
  VSS101  = GND
  CB6_B  = M_C_CPU0_SB_CB<6>
  VSS102  = GND
  CB7_B  = M_C_CPU0_SB_CB<7>
  VSS103  = GND
  DQS4_B_C  = M_C_CPU0_SB_DQS_DN<4>
  DQS4_B_T  = M_C_CPU0_SB_DQS_DP<4>
  VSS104  = GND
  CB2_B  = M_C_CPU0_SB_CB<2>
  VSS105  = GND
  CB3_B  = M_C_CPU0_SB_CB<3>
  VSS106  = GND
  DQ2_B  = M_C_CPU0_SB_DQ<2>
  VSS107  = GND
  DQ3_B  = M_C_CPU0_SB_DQ<3>
  VSS108  = GND
  \dqs5_b_c||tdqs5_b_c\  = M_C_CPU0_SB_DQS_DN<5>
  \dqs5_b_t||tdqs5_b_t\  = M_C_CPU0_SB_DQS_DP<5>
  VSS109  = GND
  DQ6_B  = M_C_CPU0_SB_DQ<6>
  VSS110  = GND
  DQ7_B  = M_C_CPU0_SB_DQ<7>
  VSS111  = GND
  DQ10_B  = M_C_CPU0_SB_DQ<10>
  VSS112  = GND
  DQ11_B  = M_C_CPU0_SB_DQ<11>
  VSS113  = GND
  \dqs6_b_c||tdqs6_b_c\  = M_C_CPU0_SB_DQS_DN<6>
  \dqs6_b_t||tdqs6_b_t\  = M_C_CPU0_SB_DQS_DP<6>
  VSS114  = GND
  DQ14_B  = M_C_CPU0_SB_DQ<14>
  VSS115  = GND
  DQ15_B  = M_C_CPU0_SB_DQ<15>
  VSS116  = GND
  DQ18_B  = M_C_CPU0_SB_DQ<18>
  VSS117  = GND
  DQ19_B  = M_C_CPU0_SB_DQ<19>
  VSS118  = GND
  \dqs7_b_c||tdqs7_b_c\  = M_C_CPU0_SB_DQS_DN<7>
  \dqs7_b_t||tdqs7_b_t\  = M_C_CPU0_SB_DQS_DP<7>
  VSS119  = GND
  DQ22_B  = M_C_CPU0_SB_DQ<22>
  VSS120  = GND
  DQ23_B  = M_C_CPU0_SB_DQ<23>
  VSS121  = GND
  DQ26_B  = M_C_CPU0_SB_DQ<26>
  VSS122  = GND
  DQ27_B  = M_C_CPU0_SB_DQ<27>
  VSS123  = GND
  \dqs8_b_c||tdqs8_b_c\  = M_C_CPU0_SB_DQS_DN<8>
  \dqs8_b_t||tdqs8_b_t\  = M_C_CPU0_SB_DQS_DP<8>
  VSS124  = GND
  DQ30_B  = M_C_CPU0_SB_DQ<30>
  VSS125  = GND
  DQ31_B  = M_C_CPU0_SB_DQ<31>
  VSS126  = GND
  G1  = GND
  G2  = GND
  G3  = GND

(kicad_pcb
	(version 20260206)
	(generator "pcbnew")
	(generator_version "10.0")
	(general
		(thickness 1.6)
		(legacy_teardrops no)
	)
	(paper "A4")
	(title_block
		(title "03242023_DA0F0TMBIJ0_F0T_Motherboard_J_brd_V01_OCP.brd")
		(comment 1 "Grand Teton / footprint 885 of 6105 (J5), pads 92-137 of 291")
	)
	(layers
		(0 "F.Cu" signal "TOP")
		(4 "In1.Cu" signal "GND")
		(6 "In2.Cu" signal "IN1")
		(8 "In3.Cu" signal "GND1")
		(10 "In4.Cu" signal "IN2")
		(12 "In5.Cu" signal "GND2")
		(14 "In6.Cu" signal "IN3")
		(16 "In7.Cu" signal "GND3")
		(18 "In8.Cu" signal "VCC")
		(20 "In9.Cu" signal "VCC1")
		(22 "In10.Cu" signal "GND4")
		(24 "In11.Cu" signal "IN4")
		(26 "In12.Cu" signal "GND5")
		(28 "In13.Cu" signal "IN5")
		(30 "In14.Cu" signal "GND6")
		(32 "In15.Cu" signal "IN6")
		(34 "In16.Cu" signal "GND7")
		(2 "B.Cu" signal "BOTTOM")
		(9 "F.Adhes" user "F.Adhesive")
		(11 "B.Adhes" user "B.Adhesive")
		(13 "F.Paste" user "Package Geometry/Pastemask Top")
		(15 "B.Paste" user "Package Geometry/Pastemask Bottom")
		(5 "F.SilkS" user "Ref Des/Silkscreen Top")
		(7 "B.SilkS" user "Ref Des/Silkscreen Bottom")
		(1 "F.Mask" user "Board Geometry/Soldermask Top")
		(3 "B.Mask" user "Board Geometry/Soldermask Bottom")
		(17 "Dwgs.User" user "User.Drawings")
		(19 "Cmts.User" user "User.Comments")
		(21 "Eco1.User" user "User.Eco1")
		(23 "Eco2.User" user "User.Eco2")
		(25 "Edge.Cuts" user "Board Geometry/Outline")
		(27 "Margin" user)
		(31 "F.CrtYd" user "Package Geometry/Place Bound Top")
		(29 "B.CrtYd" user "Package Geometry/Place Bound Bottom")
		(35 "F.Fab" user "Ref Des/Assembly Top")
		(33 "B.Fab" user "Ref Des/Assembly Bottom")
	)
	(footprint ""
		(layer "F.Cu")
		(at 273.218148 -258.091686)
		(property "Reference" "J5"
			(at -3.683 -81.702148 0)
			(unlocked yes)
			(layer "F.SilkS")
			(effects
				(font
					(size 0.7874 0.5842)
					(thickness 0.1524)
				)
				(justify left)
			)
		)
		(property "Value" ""
			(at 0 0 0)
			(layer "F.Fab")
			(effects
				(font
					(size 1.27 1.27)
				)
			)
		)
		(duplicate_pad_numbers_are_jumpers no)
		(pad "92" smd rect
			(at -2.050034 19.12493 270)
			(size 0.519938 1.4986)
			(layers "F.Cu" "F.Mask" "F.Paste")
			(net "GND")
		)
		(pad "93" smd rect
			(at -2.050034 19.975068 270)
			(size 0.519938 1.4986)
			(layers "F.Cu" "F.Mask" "F.Paste")
			(net "M_C_CPU0_SB_DQS_DP<9>")
		)
		(pad "94" smd rect
			(at -2.050034 20.824952 270)
			(size 0.519938 1.4986)
			(layers "F.Cu" "F.Mask" "F.Paste")
			(net "M_C_CPU0_SB_DQS_DN<9>")
		)
		(pad "95" smd rect
			(at -2.050034 21.67509 270)
			(size 0.519938 1.4986)
			(layers "F.Cu" "F.Mask" "F.Paste")
			(net "GND")
		)
		(pad "96" smd rect
			(at -2.050034 22.524974 270)
			(size 0.519938 1.4986)
			(layers "F.Cu" "F.Mask" "F.Paste")
			(net "M_C_CPU0_SB_CB<0>")
		)
		(pad "97" smd rect
			(at -2.050034 23.375112 270)
			(size 0.519938 1.4986)
			(layers "F.Cu" "F.Mask" "F.Paste")
			(net "GND")
		)
		(pad "98" smd rect
			(at -2.050034 24.224996 270)
			(size 0.519938 1.4986)
			(layers "F.Cu" "F.Mask" "F.Paste")
			(net "M_C_CPU0_SB_CB<1>")
		)
		(pad "99" smd rect
			(at -2.050034 25.07488 270)
			(size 0.519938 1.4986)
			(layers "F.Cu" "F.Mask" "F.Paste")
			(net "GND")
		)
		(pad "100" smd rect
			(at -2.050034 25.925018 270)
			(size 0.519938 1.4986)
			(layers "F.Cu" "F.Mask" "F.Paste")
			(net "M_C_CPU0_SB_DQ<0>")
		)
		(pad "101" smd rect
			(at -2.050034 26.774902 270)
			(size 0.519938 1.4986)
			(layers "F.Cu" "F.Mask" "F.Paste")
			(net "GND")
		)
		(pad "102" smd rect
			(at -2.050034 27.62504 270)
			(size 0.519938 1.4986)
			(layers "F.Cu" "F.Mask" "F.Paste")
			(net "M_C_CPU0_SB_DQ<1>")
		)
		(pad "103" smd rect
			(at -2.050034 28.474924 270)
			(size 0.519938 1.4986)
			(layers "F.Cu" "F.Mask" "F.Paste")
			(net "GND")
		)
		(pad "104" smd rect
			(at -2.050034 29.325062 270)
			(size 0.519938 1.4986)
			(layers "F.Cu" "F.Mask" "F.Paste")
			(net "M_C_CPU0_SB_DQS_DP<0>")
		)
		(pad "105" smd rect
			(at -2.050034 30.174946 270)
			(size 0.519938 1.4986)
			(layers "F.Cu" "F.Mask" "F.Paste")
			(net "M_C_CPU0_SB_DQS_DN<0>")
		)
		(pad "106" smd rect
			(at -2.050034 31.025084 270)
			(size 0.519938 1.4986)
			(layers "F.Cu" "F.Mask" "F.Paste")
			(net "GND")
		)
		(pad "107" smd rect
			(at -2.050034 31.874968 270)
			(size 0.519938 1.4986)
			(layers "F.Cu" "F.Mask" "F.Paste")
			(net "M_C_CPU0_SB_DQ<4>")
		)
		(pad "108" smd rect
			(at -2.050034 32.725106 270)
			(size 0.519938 1.4986)
			(layers "F.Cu" "F.Mask" "F.Paste")
			(net "GND")
		)
		(pad "109" smd rect
			(at -2.050034 33.57499 270)
			(size 0.519938 1.4986)
			(layers "F.Cu" "F.Mask" "F.Paste")
			(net "M_C_CPU0_SB_DQ<5>")
		)
		(pad "110" smd rect
			(at -2.050034 34.425128 270)
			(size 0.519938 1.4986)
			(layers "F.Cu" "F.Mask" "F.Paste")
			(net "GND")
		)
		(pad "111" smd rect
			(at -2.050034 35.275012 270)
			(size 0.519938 1.4986)
			(layers "F.Cu" "F.Mask" "F.Paste")
			(net "M_C_CPU0_SB_DQ<8>")
		)
		(pad "112" smd rect
			(at -2.050034 36.124896 270)
			(size 0.519938 1.4986)
			(layers "F.Cu" "F.Mask" "F.Paste")
			(net "GND")
		)
		(pad "113" smd rect
			(at -2.050034 36.975034 270)
			(size 0.519938 1.4986)
			(layers "F.Cu" "F.Mask" "F.Paste")
			(net "M_C_CPU0_SB_DQ<9>")
		)
		(pad "114" smd rect
			(at -2.050034 37.824918 270)
			(size 0.519938 1.4986)
			(layers "F.Cu" "F.Mask" "F.Paste")
			(net "GND")
		)
		(pad "115" smd rect
			(at -2.050034 38.675056 270)
			(size 0.519938 1.4986)
			(layers "F.Cu" "F.Mask" "F.Paste")
			(net "M_C_CPU0_SB_DQS_DP<1>")
		)
		(pad "116" smd rect
			(at -2.050034 39.52494 270)
			(size 0.519938 1.4986)
			(layers "F.Cu" "F.Mask" "F.Paste")
			(net "M_C_CPU0_SB_DQS_DN<1>")
		)
		(pad "117" smd rect
			(at -2.050034 40.375078 270)
			(size 0.519938 1.4986)
			(layers "F.Cu" "F.Mask" "F.Paste")
			(net "GND")
		)
		(pad "118" smd rect
			(at -2.050034 41.224962 270)
			(size 0.519938 1.4986)
			(layers "F.Cu" "F.Mask" "F.Paste")
			(net "M_C_CPU0_SB_DQ<12>")
		)
		(pad "119" smd rect
			(at -2.050034 42.0751 270)
			(size 0.519938 1.4986)
			(layers "F.Cu" "F.Mask" "F.Paste")
			(net "GND")
		)
		(pad "120" smd rect
			(at -2.050034 42.924984 270)
			(size 0.519938 1.4986)
			(layers "F.Cu" "F.Mask" "F.Paste")
			(net "M_C_CPU0_SB_DQ<13>")
		)
		(pad "121" smd rect
			(at -2.050034 43.775122 270)
			(size 0.519938 1.4986)
			(layers "F.Cu" "F.Mask" "F.Paste")
			(net "GND")
		)
		(pad "122" smd rect
			(at -2.050034 44.625006 270)
			(size 0.519938 1.4986)
			(layers "F.Cu" "F.Mask" "F.Paste")
			(net "M_C_CPU0_SB_DQ<16>")
		)
		(pad "123" smd rect
			(at -2.050034 45.47489 270)
			(size 0.519938 1.4986)
			(layers "F.Cu" "F.Mask" "F.Paste")
			(net "GND")
		)
		(pad "124" smd rect
			(at -2.050034 46.325028 270)
			(size 0.519938 1.4986)
			(layers "F.Cu" "F.Mask" "F.Paste")
			(net "M_C_CPU0_SB_DQ<17>")
		)
		(pad "125" smd rect
			(at -2.050034 47.174912 270)
			(size 0.519938 1.4986)
			(layers "F.Cu" "F.Mask" "F.Paste")
			(net "GND")
		)
		(pad "126" smd rect
			(at -2.050034 48.02505 270)
			(size 0.519938 1.4986)
			(layers "F.Cu" "F.Mask" "F.Paste")
			(net "M_C_CPU0_SB_DQS_DP<2>")
		)
		(pad "127" smd rect
			(at -2.050034 48.874934 270)
			(size 0.519938 1.4986)
			(layers "F.Cu" "F.Mask" "F.Paste")
			(net "M_C_CPU0_SB_DQS_DN<2>")
		)
		(pad "128" smd rect
			(at -2.050034 49.725072 270)
			(size 0.519938 1.4986)
			(layers "F.Cu" "F.Mask" "F.Paste")
			(net "GND")
		)
		(pad "129" smd rect
			(at -2.050034 50.574956 270)
			(size 0.519938 1.4986)
			(layers "F.Cu" "F.Mask" "F.Paste")
			(net "M_C_CPU0_SB_DQ<20>")
		)
		(pad "130" smd rect
			(at -2.050034 51.425094 270)
			(size 0.519938 1.4986)
			(layers "F.Cu" "F.Mask" "F.Paste")
			(net "GND")
		)
		(pad "131" smd rect
			(at -2.050034 52.274978 270)
			(size 0.519938 1.4986)
			(layers "F.Cu" "F.Mask" "F.Paste")
			(net "M_C_CPU0_SB_DQ<21>")
		)
		(pad "132" smd rect
			(at -2.050034 53.125116 270)
			(size 0.519938 1.4986)
			(layers "F.Cu" "F.Mask" "F.Paste")
			(net "GND")
		)
		(pad "133" smd rect
			(at -2.050034 53.975 270)
			(size 0.519938 1.4986)
			(layers "F.Cu" "F.Mask" "F.Paste")
			(net "M_C_CPU0_SB_DQ<24>")
		)
		(pad "134" smd rect
			(at -2.050034 54.824884 270)
			(size 0.519938 1.4986)
			(layers "F.Cu" "F.Mask" "F.Paste")
			(net "GND")
		)
		(pad "135" smd rect
			(at -2.050034 55.675022 270)
			(size 0.519938 1.4986)
			(layers "F.Cu" "F.Mask" "F.Paste")
			(net "M_C_CPU0_SB_DQ<25>")
		)
		(pad "136" smd rect
			(at -2.050034 56.524906 270)
			(size 0.519938 1.4986)
			(layers "F.Cu" "F.Mask" "F.Paste")
			(net "GND")
		)
		(pad "137" smd rect
			(at -2.050034 57.375044 270)
			(size 0.519938 1.4986)
			(layers "F.Cu" "F.Mask" "F.Paste")
			(net "M_C_CPU0_SB_DQS_DP<3>")
		)
	)
)
